# T6G (Grand Teton) — schematic netlist excerpt (pin names and nets, part order shuffled) for the footprints in the layout excerpt that follows; sources: Cadence DE-HDL packaged netlist, KiCad conversion of 04192023_DAF0TMB3IC0_F0TG_MB_C_brd_V02_OCP.brd

U98  PCA9306DP1  IC  pkg TSSOP8_3  page 148
  GND  = GND
  VREF1  = P1V8_AUX
  SCL1  = SMB_M2_P1_1V8AUX_SCL_R
  SDA1  = SMB_M2_P1_1V8AUX_SDA_R
  SDA2  = SMB_SENSOR_M2_P1_3V3AUX_SDA
  SCL2  = SMB_SENSOR_M2_P1_3V3AUX_SCL
  VREF2  = SMB_PCIE_M2_0_EN
  EN  = SMB_PCIE_M2_0_EN

PC316  Q_CAP  560PF 50V 10% EMPTY  pkg C0402  page 212 : A = SW_PVDDCR_CPU0_P1_SW3 ; B = SW_PVDDCR_CPU0_P1_SW3_RC

(kicad_pcb
	(version 20260206)
	(generator "pcbnew")
	(generator_version "10.0")
	(general
		(thickness 1.6)
		(legacy_teardrops no)
	)
	(paper "A4")
	(title_block
		(title "04192023_DAF0TMB3IC0_F0TG_MB_C_brd_V02_OCP.brd")
		(comment 1 "Grand Teton / footprints 1277-1278 of 8354")
	)
	(layers
		(0 "F.Cu" signal "TOP")
		(4 "In1.Cu" signal "GND")
		(6 "In2.Cu" signal "IN1")
		(8 "In3.Cu" signal "GND1")
		(10 "In4.Cu" signal "IN2")
		(12 "In5.Cu" signal "GND2")
		(14 "In6.Cu" signal "IN3")
		(16 "In7.Cu" signal "GND3")
		(18 "In8.Cu" signal "VCC")
		(20 "In9.Cu" signal "VCC1")
		(22 "In10.Cu" signal "GND4")
		(24 "In11.Cu" signal "IN4")
		(26 "In12.Cu" signal "GND5")
		(28 "In13.Cu" signal "IN5")
		(30 "In14.Cu" signal "GND6")
		(32 "In15.Cu" signal "IN6")
		(34 "In16.Cu" signal "GND7")
		(2 "B.Cu" signal "BOTTOM")
		(9 "F.Adhes" user "F.Adhesive")
		(11 "B.Adhes" user "B.Adhesive")
		(13 "F.Paste" user "Package Geometry/Pastemask Top")
		(15 "B.Paste" user "Package Geometry/Pastemask Bottom")
		(5 "F.SilkS" user "Ref Des/Silkscreen Top")
		(7 "B.SilkS" user "Ref Des/Silkscreen Bottom")
		(1 "F.Mask" user "Board Geometry/Soldermask Top")
		(3 "B.Mask" user "Board Geometry/Soldermask Bottom")
		(17 "Dwgs.User" user "User.Drawings")
		(19 "Cmts.User" user "User.Comments")
		(21 "Eco1.User" user "User.Eco1")
		(23 "Eco2.User" user "User.Eco2")
		(25 "Edge.Cuts" user "Board Geometry/Outline")
		(27 "Margin" user)
		(31 "F.CrtYd" user "Package Geometry/Place Bound Top")
		(29 "B.CrtYd" user "Package Geometry/Place Bound Bottom")
		(35 "F.Fab" user "Ref Des/Assembly Top")
		(33 "B.Fab" user "Ref Des/Assembly Bottom")
	)
	(footprint ""
		(layer "F.Cu")
		(at 153.416508 -43.61053)
		(property "Reference" "U98"
			(at -1.397 -2.13233 0)
			(unlocked yes)
			(layer "F.SilkS")
			(effects
				(font
					(size 0.7874 0.5842)
					(thickness 0.1524)
				)
				(justify left)
			)
		)
		(property "Value" ""
			(at 0 0 0)
			(layer "F.Fab")
			(effects
				(font
					(size 1.27 1.27)
				)
			)
		)
		(duplicate_pad_numbers_are_jumpers no)
		(fp_line
			(start -1.3208 -1.525016)
			(end -0.508 -1.525016)
			(stroke
				(width 0.1524)
				(type default)
			)
			(layer "F.SilkS")
		)
		(fp_line
			(start -1.3208 1.525016)
			(end -1.3208 -1.525016)
			(stroke
				(width 0.1524)
				(type default)
			)
			(layer "F.SilkS")
		)
		(fp_line
			(start -0.508 -1.525016)
			(end 0 -0.999998)
			(stroke
				(width 0.1524)
				(type default)
			)
			(layer "F.SilkS")
		)
		(fp_line
			(start 0 -0.999998)
			(end 0.508 -1.525016)
			(stroke
				(width 0.1524)
				(type default)
			)
			(layer "F.SilkS")
		)
		(fp_line
			(start 0.508 -1.525016)
			(end 1.3208 -1.525016)
			(stroke
				(width 0.1524)
				(type default)
			)
			(layer "F.SilkS")
		)
		(fp_line
			(start 1.3208 -1.525016)
			(end 1.3208 1.525016)
			(stroke
				(width 0.1524)
				(type default)
			)
			(layer "F.SilkS")
		)
		(fp_line
			(start 1.3208 1.525016)
			(end -1.3208 1.525016)
			(stroke
				(width 0.1524)
				(type default)
			)
			(layer "F.SilkS")
		)
		(fp_poly
			(pts
				(xy -2.176018 -2.256282) (xy -2.557018 -1.494282) (xy -2.938018 -2.256282)
			)
			(stroke
				(width 0)
				(type default)
			)
			(fill yes)
			(layer "F.SilkS")
		)
		(fp_line
			(start -3.037078 -1.20777)
			(end -1.524 -1.20777)
			(stroke
				(width 0.1)
				(type default)
			)
			(layer "F.Fab")
		)
		(fp_line
			(start -3.037078 1.203706)
			(end -3.037078 -1.20777)
			(stroke
				(width 0.1)
				(type default)
			)
			(layer "F.Fab")
		)
		(fp_line
			(start -1.5494 1.203706)
			(end -3.037078 1.203706)
			(stroke
				(width 0.1)
				(type default)
			)
			(layer "F.Fab")
		)
		(fp_line
			(start -1.5494 1.5494)
			(end -1.5494 1.203706)
			(stroke
				(width 0.1)
				(type default)
			)
			(layer "F.Fab")
		)
		(fp_line
			(start -1.524 -1.524)
			(end 1.524 -1.524)
			(stroke
				(width 0.1)
				(type default)
			)
			(layer "F.Fab")
		)
		(fp_line
			(start -1.524 -1.20777)
			(end -1.524 -1.524)
			(stroke
				(width 0.1)
				(type default)
			)
			(layer "F.Fab")
		)
		(fp_line
			(start 1.524 -1.524)
			(end 1.524 -1.20777)
			(stroke
				(width 0.1)
				(type default)
			)
			(layer "F.Fab")
		)
		(fp_line
			(start 1.524 -1.20777)
			(end 3.0353 -1.20777)
			(stroke
				(width 0.1)
				(type default)
			)
			(layer "F.Fab")
		)
		(fp_line
			(start 1.524 1.208786)
			(end 1.524 1.5494)
			(stroke
				(width 0.1)
				(type default)
			)
			(layer "F.Fab")
		)
		(fp_line
			(start 1.524 1.5494)
			(end -1.5494 1.5494)
			(stroke
				(width 0.1)
				(type default)
			)
			(layer "F.Fab")
		)
		(fp_line
			(start 3.0353 -1.20777)
			(end 3.0353 1.208786)
			(stroke
				(width 0.1)
				(type default)
			)
			(layer "F.Fab")
		)
		(fp_line
			(start 3.0353 1.208786)
			(end 1.524 1.208786)
			(stroke
				(width 0.1)
				(type default)
			)
			(layer "F.Fab")
		)
		(fp_poly
			(pts
				(xy -3.175 -1.016) (xy -3.937 -0.635) (xy -3.937 -1.397)
			)
			(stroke
				(width 0)
				(type default)
			)
			(fill yes)
			(layer "F.Fab")
		)
		(pad "1" smd rect
			(at -2.234946 -0.975106 270)
			(size 0.3556 1.4986)
			(layers "F.Cu" "F.Mask" "F.Paste")
			(net "GND")
		)
		(pad "2" smd rect
			(at -2.234946 -0.32512 270)
			(size 0.3556 1.4986)
			(layers "F.Cu" "F.Mask" "F.Paste")
			(net "P1V8_AUX")
		)
		(pad "3" smd rect
			(at -2.234946 0.32512 270)
			(size 0.3556 1.4986)
			(layers "F.Cu" "F.Mask" "F.Paste")
			(net "SMB_M2_P1_1V8AUX_SCL_R")
		)
		(pad "4" smd rect
			(at -2.234946 0.975106 270)
			(size 0.3556 1.4986)
			(layers "F.Cu" "F.Mask" "F.Paste")
			(net "SMB_M2_P1_1V8AUX_SDA_R")
		)
		(pad "5" smd rect
			(at 2.234946 0.975106 270)
			(size 0.3556 1.4986)
			(layers "F.Cu" "F.Mask" "F.Paste")
			(net "SMB_SENSOR_M2_P1_3V3AUX_SDA")
		)
		(pad "6" smd rect
			(at 2.234946 0.32512 270)
			(size 0.3556 1.4986)
			(layers "F.Cu" "F.Mask" "F.Paste")
			(net "SMB_SENSOR_M2_P1_3V3AUX_SCL")
		)
		(pad "7" smd rect
			(at 2.234946 -0.32512 270)
			(size 0.3556 1.4986)
			(layers "F.Cu" "F.Mask" "F.Paste")
			(net "SMB_PCIE_M2_0_EN")
		)
		(pad "8" smd rect
			(at 2.234946 -0.975106 270)
			(size 0.3556 1.4986)
			(layers "F.Cu" "F.Mask" "F.Paste")
			(net "SMB_PCIE_M2_0_EN")
		)
	)
	(footprint ""
		(layer "F.Cu")
		(at 102.767892 -185.697368)
		(property "Reference" "PC316"
			(at 0 0 0)
			(layer "F.SilkS")
			(hide yes)
			(effects
				(font
					(size 1.27 1.27)
				)
			)
		)
		(property "Value" ""
			(at 0 0 0)
			(layer "F.Fab")
			(effects
				(font
					(size 1.27 1.27)
				)
			)
		)
		(duplicate_pad_numbers_are_jumpers no)
		(fp_line
			(start -0.7874 -0.4064)
			(end 0.7874 -0.4064)
			(stroke
				(width 0.1524)
				(type default)
			)
			(layer "F.SilkS")
		)
		(fp_line
			(start -0.7874 0.4064)
			(end -0.7874 -0.4064)
			(stroke
				(width 0.1524)
				(type default)
			)
			(layer "F.SilkS")
		)
		(fp_line
			(start 0.7874 -0.4064)
			(end 0.7874 0.4064)
			(stroke
				(width 0.1524)
				(type default)
			)
			(layer "F.SilkS")
		)
		(fp_line
			(start 0.7874 0.4064)
			(end -0.7874 0.4064)
			(stroke
				(width 0.1524)
				(type default)
			)
			(layer "F.SilkS")
		)
		(fp_line
			(start -0.67945 -0.305054)
			(end -0.12065 -0.305054)
			(stroke
				(width 0.1)
				(type default)
			)
			(layer "F.Fab")
		)
		(fp_line
			(start -0.67945 0.3048)
			(end -0.67945 -0.305054)
			(stroke
				(width 0.1)
				(type default)
			)
			(layer "F.Fab")
		)
		(fp_line
			(start -0.12065 -0.305054)
			(end -0.12065 -0.2794)
			(stroke
				(width 0.1)
				(type default)
			)
			(layer "F.Fab")
		)
		(fp_line
			(start -0.12065 -0.2794)
			(end 0.12065 -0.2794)
			(stroke
				(width 0.1)
				(type default)
			)
			(layer "F.Fab")
		)
		(fp_line
			(start -0.12065 0.2794)
			(end -0.12065 0.3048)
			(stroke
				(width 0.1)
				(type default)
			)
			(layer "F.Fab")
		)
		(fp_line
			(start -0.12065 0.3048)
			(end -0.67945 0.3048)
			(stroke
				(width 0.1)
				(type default)
			)
			(layer "F.Fab")
		)
		(fp_line
			(start 0.120396 0.2794)
			(end -0.12065 0.2794)
			(stroke
				(width 0.1)
				(type default)
			)
			(layer "F.Fab")
		)
		(fp_line
			(start 0.120396 0.3048)
			(end 0.120396 0.2794)
			(stroke
				(width 0.1)
				(type default)
			)
			(layer "F.Fab")
		)
		(fp_line
			(start 0.12065 -0.3048)
			(end 0.67945 -0.3048)
			(stroke
				(width 0.1)
				(type default)
			)
			(layer "F.Fab")
		)
		(fp_line
			(start 0.12065 -0.2794)
			(end 0.12065 -0.3048)
			(stroke
				(width 0.1)
				(type default)
			)
			(layer "F.Fab")
		)
		(fp_line
			(start 0.67945 -0.3048)
			(end 0.67945 0.3048)
			(stroke
				(width 0.1)
				(type default)
			)
			(layer "F.Fab")
		)
		(fp_line
			(start 0.67945 0.3048)
			(end 0.120396 0.3048)
			(stroke
				(width 0.1)
				(type default)
			)
			(layer "F.Fab")
		)
		(pad "1" smd circle
			(at -0.40005 0)
			(size 0 0)
			(layers "F.Cu" "F.Mask" "F.Paste")
			(net "SW_PVDDCR_CPU0_P1_SW3")
		)
		(pad "2" smd circle
			(at 0.40005 0)
			(size 0 0)
			(layers "F.Cu" "F.Mask" "F.Paste")
			(net "SW_PVDDCR_CPU0_P1_SW3_RC")
		)
	)
)
